# BARRELEYE_G2-FPDB_POST-EVT-HW-EBOM-X00_20161123-add_2nd_source_X08-20161215-Final-b.xls — Single-Sole Source Parts List (bom)
| FOXCONN TECHNOLOGY GROUP |  |  |  |  |  |  |  |  |  |  |  |  |  |  |  |  |  |
| BILL OF MATERIAL |  |  |  |  |  |  |  |  |  |  |  |  |  |  |  |  |  |
| REV OF  BOM |  | CUSTOMER | <name> |  | CUSTOMER P/N |  | PWA P/N： | PWA DESCRIPTION |  |  | PRODUCT CODE |  |  | PWA REV |  | DATE |  |
| Sourcing (Single or Sole | Critical Commodity (Y or N) | Component Class (1, 2, Other) | Customer PSL (Y/N) | Item Number | Foxconn P/N | Customer P/N | Part Description | Mfr. 1 | Mfr Part # 1 | Proposed Mfr. 2 | Proposed Mfr. 2 PN | Qty | RoHS Status | Location | 2nd Source Qual Build: | Customer Comments | ODM Comments |
